# SCM (Grand Teton) — schematic netlist excerpt (pin names and nets, part order shuffled) for the footprints in the layout excerpt that follows; sources: Cadence DE-HDL packaged netlist, KiCad conversion of 12092022_DA0F0TMDCD0_F0T_Management_Board_D_brd_V3_OCP.brd

R764  Q_RES  0 5% EMPTY  pkg 0402LF  page 55 : A = PWRGD_P1V8_AUX ; B = EN_P1V2_AUX_R
R708  Q_RES  0 5% CHIP  pkg 0402LF  page 55 : A = EN_P1V2_AUX ; B = EN_P1V2_AUX_R

(kicad_pcb
	(version 20260206)
	(generator "pcbnew")
	(generator_version "10.0")
	(general
		(thickness 1.6)
		(legacy_teardrops no)
	)
	(paper "A4")
	(title_block
		(title "12092022_DA0F0TMDCD0_F0T_Management_Board_D_brd_V3_OCP.brd")
		(comment 1 "Grand Teton / footprints 626-627 of 1440")
	)
	(layers
		(0 "F.Cu" signal "TOP")
		(4 "In1.Cu" signal "GND")
		(6 "In2.Cu" signal "IN1")
		(8 "In3.Cu" signal "GND1")
		(10 "In4.Cu" signal "IN2")
		(12 "In5.Cu" signal "VCC")
		(14 "In6.Cu" signal "VCC1")
		(16 "In7.Cu" signal "IN3")
		(18 "In8.Cu" signal "GND2")
		(20 "In9.Cu" signal "IN4")
		(22 "In10.Cu" signal "GND3")
		(2 "B.Cu" signal "BOTTOM")
		(9 "F.Adhes" user "F.Adhesive")
		(11 "B.Adhes" user "B.Adhesive")
		(13 "F.Paste" user "Package Geometry/Pastemask Top")
		(15 "B.Paste" user "Package Geometry/Pastemask Bottom")
		(5 "F.SilkS" user "Ref Des/Silkscreen Top")
		(7 "B.SilkS" user "Ref Des/Silkscreen Bottom")
		(1 "F.Mask" user "Board Geometry/Soldermask Top")
		(3 "B.Mask" user "Board Geometry/Soldermask Bottom")
		(17 "Dwgs.User" user "User.Drawings")
		(19 "Cmts.User" user "User.Comments")
		(21 "Eco1.User" user "User.Eco1")
		(23 "Eco2.User" user "User.Eco2")
		(25 "Edge.Cuts" user "Board Geometry/Outline")
		(27 "Margin" user)
		(31 "F.CrtYd" user "Package Geometry/Place Bound Top")
		(29 "B.CrtYd" user "Package Geometry/Place Bound Bottom")
		(35 "F.Fab" user "Ref Des/Assembly Top")
		(33 "B.Fab" user "Ref Des/Assembly Bottom")
	)
	(footprint ""
		(layer "F.Cu")
		(at 77.947774 -72.413368)
		(property "Reference" "R764"
			(at 0 0 0)
			(layer "F.SilkS")
			(hide yes)
			(effects
				(font
					(size 1.27 1.27)
				)
			)
		)
		(property "Value" ""
			(at 0 0 0)
			(layer "F.Fab")
			(effects
				(font
					(size 1.27 1.27)
				)
			)
		)
		(duplicate_pad_numbers_are_jumpers no)
		(fp_line
			(start -0.7874 -0.4064)
			(end 0.7874 -0.4064)
			(stroke
				(width 0.1524)
				(type default)
			)
			(layer "F.SilkS")
		)
		(fp_line
			(start -0.7874 0.4064)
			(end -0.7874 -0.4064)
			(stroke
				(width 0.1524)
				(type default)
			)
			(layer "F.SilkS")
		)
		(fp_line
			(start 0.7874 -0.4064)
			(end 0.7874 0.4064)
			(stroke
				(width 0.1524)
				(type default)
			)
			(layer "F.SilkS")
		)
		(fp_line
			(start 0.7874 0.4064)
			(end -0.7874 0.4064)
			(stroke
				(width 0.1524)
				(type default)
			)
			(layer "F.SilkS")
		)
		(fp_line
			(start -0.67945 -0.305054)
			(end -0.12065 -0.305054)
			(stroke
				(width 0.1)
				(type default)
			)
			(layer "F.Fab")
		)
		(fp_line
			(start -0.67945 0.3048)
			(end -0.67945 -0.305054)
			(stroke
				(width 0.1)
				(type default)
			)
			(layer "F.Fab")
		)
		(fp_line
			(start -0.12065 -0.305054)
			(end -0.12065 -0.2794)
			(stroke
				(width 0.1)
				(type default)
			)
			(layer "F.Fab")
		)
		(fp_line
			(start -0.12065 -0.2794)
			(end 0.12065 -0.2794)
			(stroke
				(width 0.1)
				(type default)
			)
			(layer "F.Fab")
		)
		(fp_line
			(start -0.12065 0.2794)
			(end -0.12065 0.3048)
			(stroke
				(width 0.1)
				(type default)
			)
			(layer "F.Fab")
		)
		(fp_line
			(start -0.12065 0.3048)
			(end -0.67945 0.3048)
			(stroke
				(width 0.1)
				(type default)
			)
			(layer "F.Fab")
		)
		(fp_line
			(start 0.120396 0.2794)
			(end -0.12065 0.2794)
			(stroke
				(width 0.1)
				(type default)
			)
			(layer "F.Fab")
		)
		(fp_line
			(start 0.120396 0.3048)
			(end 0.120396 0.2794)
			(stroke
				(width 0.1)
				(type default)
			)
			(layer "F.Fab")
		)
		(fp_line
			(start 0.12065 -0.3048)
			(end 0.67945 -0.3048)
			(stroke
				(width 0.1)
				(type default)
			)
			(layer "F.Fab")
		)
		(fp_line
			(start 0.12065 -0.2794)
			(end 0.12065 -0.3048)
			(stroke
				(width 0.1)
				(type default)
			)
			(layer "F.Fab")
		)
		(fp_line
			(start 0.67945 -0.3048)
			(end 0.67945 0.3048)
			(stroke
				(width 0.1)
				(type default)
			)
			(layer "F.Fab")
		)
		(fp_line
			(start 0.67945 0.3048)
			(end 0.120396 0.3048)
			(stroke
				(width 0.1)
				(type default)
			)
			(layer "F.Fab")
		)
		(pad "1" smd circle
			(at -0.40005 0)
			(size 0 0)
			(layers "F.Cu" "F.Mask" "F.Paste")
			(net "PWRGD_P1V8_AUX")
		)
		(pad "2" smd circle
			(at 0.40005 0)
			(size 0 0)
			(layers "F.Cu" "F.Mask" "F.Paste")
			(net "EN_P1V2_AUX_R")
		)
	)
	(footprint ""
		(layer "F.Cu")
		(at 77.947774 -71.396352)
		(property "Reference" "R708"
			(at 0 0 0)
			(layer "F.SilkS")
			(hide yes)
			(effects
				(font
					(size 1.27 1.27)
				)
			)
		)
		(property "Value" ""
			(at 0 0 0)
			(layer "F.Fab")
			(effects
				(font
					(size 1.27 1.27)
				)
			)
		)
		(duplicate_pad_numbers_are_jumpers no)
		(fp_line
			(start -0.7874 -0.4064)
			(end 0.7874 -0.4064)
			(stroke
				(width 0.1524)
				(type default)
			)
			(layer "F.SilkS")
		)
		(fp_line
			(start -0.7874 0.4064)
			(end -0.7874 -0.4064)
			(stroke
				(width 0.1524)
				(type default)
			)
			(layer "F.SilkS")
		)
		(fp_line
			(start 0.7874 -0.4064)
			(end 0.7874 0.4064)
			(stroke
				(width 0.1524)
				(type default)
			)
			(layer "F.SilkS")
		)
		(fp_line
			(start 0.7874 0.4064)
			(end -0.7874 0.4064)
			(stroke
				(width 0.1524)
				(type default)
			)
			(layer "F.SilkS")
		)
		(fp_line
			(start -0.67945 -0.305054)
			(end -0.12065 -0.305054)
			(stroke
				(width 0.1)
				(type default)
			)
			(layer "F.Fab")
		)
		(fp_line
			(start -0.67945 0.3048)
			(end -0.67945 -0.305054)
			(stroke
				(width 0.1)
				(type default)
			)
			(layer "F.Fab")
		)
		(fp_line
			(start -0.12065 -0.305054)
			(end -0.12065 -0.2794)
			(stroke
				(width 0.1)
				(type default)
			)
			(layer "F.Fab")
		)
		(fp_line
			(start -0.12065 -0.2794)
			(end 0.12065 -0.2794)
			(stroke
				(width 0.1)
				(type default)
			)
			(layer "F.Fab")
		)
		(fp_line
			(start -0.12065 0.2794)
			(end -0.12065 0.3048)
			(stroke
				(width 0.1)
				(type default)
			)
			(layer "F.Fab")
		)
		(fp_line
			(start -0.12065 0.3048)
			(end -0.67945 0.3048)
			(stroke
				(width 0.1)
				(type default)
			)
			(layer "F.Fab")
		)
		(fp_line
			(start 0.120396 0.2794)
			(end -0.12065 0.2794)
			(stroke
				(width 0.1)
				(type default)
			)
			(layer "F.Fab")
		)
		(fp_line
			(start 0.120396 0.3048)
			(end 0.120396 0.2794)
			(stroke
				(width 0.1)
				(type default)
			)
			(layer "F.Fab")
		)
		(fp_line
			(start 0.12065 -0.3048)
			(end 0.67945 -0.3048)
			(stroke
				(width 0.1)
				(type default)
			)
			(layer "F.Fab")
		)
		(fp_line
			(start 0.12065 -0.2794)
			(end 0.12065 -0.3048)
			(stroke
				(width 0.1)
				(type default)
			)
			(layer "F.Fab")
		)
		(fp_line
			(start 0.67945 -0.3048)
			(end 0.67945 0.3048)
			(stroke
				(width 0.1)
				(type default)
			)
			(layer "F.Fab")
		)
		(fp_line
			(start 0.67945 0.3048)
			(end 0.120396 0.3048)
			(stroke
				(width 0.1)
				(type default)
			)
			(layer "F.Fab")
		)
		(pad "1" smd circle
			(at -0.40005 0)
			(size 0 0)
			(layers "F.Cu" "F.Mask" "F.Paste")
			(net "EN_P1V2_AUX")
		)
		(pad "2" smd circle
			(at 0.40005 0)
			(size 0 0)
			(layers "F.Cu" "F.Mask" "F.Paste")
			(net "EN_P1V2_AUX_R")
		)
	)
)
